# SCM (Grand Teton) — schematic netlist excerpt (pin names and nets, part order shuffled) for the footprints in the layout excerpt that follows; sources: Cadence DE-HDL packaged netlist, KiCad conversion of 12092022_DA0F0TMDCD0_F0T_Management_Board_D_brd_V3_OCP.brd

R215  Q_RES  33.2 1% CHIP  pkg 0402LF  page 15 : A = BMC_CLK_25M_R ; B = BMC_CLK_25M

U43  TPS3808G18DBVR  TPS3808G01DBVR IC  pkg SOT23-6XD  page 22
  \#reset\  = PWRGD_P1V0_AUX_DELAY_R1
  GND  = GND
  \#mr\  = PWRGD_P1V0_AUX_R2
  CT  = U43_CT
  SENSE  = P1V0_AUX
  VDD  = P3V3_AUX

(kicad_pcb
	(version 20260206)
	(generator "pcbnew")
	(generator_version "10.0")
	(general
		(thickness 1.6)
		(legacy_teardrops no)
	)
	(paper "A4")
	(title_block
		(title "12092022_DA0F0TMDCD0_F0T_Management_Board_D_brd_V3_OCP.brd")
		(comment 1 "Grand Teton / footprints 23-24 of 1440")
	)
	(layers
		(0 "F.Cu" signal "TOP")
		(4 "In1.Cu" signal "GND")
		(6 "In2.Cu" signal "IN1")
		(8 "In3.Cu" signal "GND1")
		(10 "In4.Cu" signal "IN2")
		(12 "In5.Cu" signal "VCC")
		(14 "In6.Cu" signal "VCC1")
		(16 "In7.Cu" signal "IN3")
		(18 "In8.Cu" signal "GND2")
		(20 "In9.Cu" signal "IN4")
		(22 "In10.Cu" signal "GND3")
		(2 "B.Cu" signal "BOTTOM")
		(9 "F.Adhes" user "F.Adhesive")
		(11 "B.Adhes" user "B.Adhesive")
		(13 "F.Paste" user "Package Geometry/Pastemask Top")
		(15 "B.Paste" user "Package Geometry/Pastemask Bottom")
		(5 "F.SilkS" user "Ref Des/Silkscreen Top")
		(7 "B.SilkS" user "Ref Des/Silkscreen Bottom")
		(1 "F.Mask" user "Board Geometry/Soldermask Top")
		(3 "B.Mask" user "Board Geometry/Soldermask Bottom")
		(17 "Dwgs.User" user "User.Drawings")
		(19 "Cmts.User" user "User.Comments")
		(21 "Eco1.User" user "User.Eco1")
		(23 "Eco2.User" user "User.Eco2")
		(25 "Edge.Cuts" user "Board Geometry/Outline")
		(27 "Margin" user)
		(31 "F.CrtYd" user "Package Geometry/Place Bound Top")
		(29 "B.CrtYd" user "Package Geometry/Place Bound Bottom")
		(35 "F.Fab" user "Ref Des/Assembly Top")
		(33 "B.Fab" user "Ref Des/Assembly Bottom")
	)
	(footprint ""
		(layer "F.Cu")
		(at 59.5884 -27.813 -90)
		(property "Reference" "R215"
			(at 0 0 270)
			(layer "F.SilkS")
			(hide yes)
			(effects
				(font
					(size 1.27 1.27)
				)
			)
		)
		(property "Value" ""
			(at 0 0 270)
			(layer "F.Fab")
			(effects
				(font
					(size 1.27 1.27)
				)
			)
		)
		(duplicate_pad_numbers_are_jumpers no)
		(fp_line
			(start -0.7874 0.4064)
			(end -0.7874 -0.4064)
			(stroke
				(width 0.1524)
				(type default)
			)
			(layer "F.SilkS")
		)
		(fp_line
			(start 0.7874 0.4064)
			(end -0.7874 0.4064)
			(stroke
				(width 0.1524)
				(type default)
			)
			(layer "F.SilkS")
		)
		(fp_line
			(start -0.7874 -0.4064)
			(end 0.7874 -0.4064)
			(stroke
				(width 0.1524)
				(type default)
			)
			(layer "F.SilkS")
		)
		(fp_line
			(start 0.7874 -0.4064)
			(end 0.7874 0.4064)
			(stroke
				(width 0.1524)
				(type default)
			)
			(layer "F.SilkS")
		)
		(fp_line
			(start -0.67945 0.3048)
			(end -0.67945 -0.305054)
			(stroke
				(width 0.1)
				(type default)
			)
			(layer "F.Fab")
		)
		(fp_line
			(start -0.12065 0.3048)
			(end -0.67945 0.3048)
			(stroke
				(width 0.1)
				(type default)
			)
			(layer "F.Fab")
		)
		(fp_line
			(start 0.120396 0.3048)
			(end 0.120396 0.2794)
			(stroke
				(width 0.1)
				(type default)
			)
			(layer "F.Fab")
		)
		(fp_line
			(start 0.67945 0.3048)
			(end 0.120396 0.3048)
			(stroke
				(width 0.1)
				(type default)
			)
			(layer "F.Fab")
		)
		(fp_line
			(start -0.12065 0.2794)
			(end -0.12065 0.3048)
			(stroke
				(width 0.1)
				(type default)
			)
			(layer "F.Fab")
		)
		(fp_line
			(start 0.120396 0.2794)
			(end -0.12065 0.2794)
			(stroke
				(width 0.1)
				(type default)
			)
			(layer "F.Fab")
		)
		(fp_line
			(start -0.12065 -0.2794)
			(end 0.12065 -0.2794)
			(stroke
				(width 0.1)
				(type default)
			)
			(layer "F.Fab")
		)
		(fp_line
			(start 0.12065 -0.2794)
			(end 0.12065 -0.3048)
			(stroke
				(width 0.1)
				(type default)
			)
			(layer "F.Fab")
		)
		(fp_line
			(start 0.12065 -0.3048)
			(end 0.67945 -0.3048)
			(stroke
				(width 0.1)
				(type default)
			)
			(layer "F.Fab")
		)
		(fp_line
			(start 0.67945 -0.3048)
			(end 0.67945 0.3048)
			(stroke
				(width 0.1)
				(type default)
			)
			(layer "F.Fab")
		)
		(fp_line
			(start -0.67945 -0.305054)
			(end -0.12065 -0.305054)
			(stroke
				(width 0.1)
				(type default)
			)
			(layer "F.Fab")
		)
		(fp_line
			(start -0.12065 -0.305054)
			(end -0.12065 -0.2794)
			(stroke
				(width 0.1)
				(type default)
			)
			(layer "F.Fab")
		)
		(pad "1" smd circle
			(at -0.40005 0 270)
			(size 0 0)
			(layers "F.Cu" "F.Mask" "F.Paste")
			(net "BMC_CLK_25M_R")
		)
		(pad "2" smd circle
			(at 0.40005 0 270)
			(size 0 0)
			(layers "F.Cu" "F.Mask" "F.Paste")
			(net "BMC_CLK_25M")
		)
	)
	(footprint ""
		(layer "F.Cu")
		(at 33.909 -40.2082 90)
		(property "Reference" "U43"
			(at -0.8128 -2.31013 90)
			(unlocked yes)
			(layer "F.SilkS")
			(effects
				(font
					(size 0.7874 0.5842)
					(thickness 0.1524)
				)
			)
		)
		(property "Value" ""
			(at 0 0 90)
			(layer "F.Fab")
			(effects
				(font
					(size 1.27 1.27)
				)
			)
		)
		(duplicate_pad_numbers_are_jumpers no)
		(fp_line
			(start 2.032 -1.525016)
			(end 2.032 1.525016)
			(stroke
				(width 0.1524)
				(type default)
			)
			(layer "F.SilkS")
		)
		(fp_line
			(start 0.635 -1.525016)
			(end 2.032 -1.525016)
			(stroke
				(width 0.1524)
				(type default)
			)
			(layer "F.SilkS")
		)
		(fp_line
			(start -0.635 -1.525016)
			(end 0 -0.889)
			(stroke
				(width 0.1524)
				(type default)
			)
			(layer "F.SilkS")
		)
		(fp_line
			(start -2.032 -1.525016)
			(end -0.635 -1.525016)
			(stroke
				(width 0.1524)
				(type default)
			)
			(layer "F.SilkS")
		)
		(fp_line
			(start 0 -0.889)
			(end 0.635 -1.525016)
			(stroke
				(width 0.1524)
				(type default)
			)
			(layer "F.SilkS")
		)
		(fp_line
			(start 2.032 1.525016)
			(end -2.032 1.525016)
			(stroke
				(width 0.1524)
				(type default)
			)
			(layer "F.SilkS")
		)
		(fp_line
			(start -2.032 1.525016)
			(end -2.032 -1.525016)
			(stroke
				(width 0.1524)
				(type default)
			)
			(layer "F.SilkS")
		)
		(fp_poly
			(pts
				(xy -2.9718 -1.33096) (xy -2.9718 -0.56896) (xy -2.2098 -0.94996)
			)
			(stroke
				(width 0)
				(type default)
			)
			(fill yes)
			(layer "F.SilkS")
		)
		(fp_line
			(start 0.87503 -1.525016)
			(end 0.87503 1.525016)
			(stroke
				(width 0.1)
				(type default)
			)
			(layer "F.Fab")
		)
		(fp_line
			(start -0.87503 -1.525016)
			(end 0.87503 -1.525016)
			(stroke
				(width 0.1)
				(type default)
			)
			(layer "F.Fab")
		)
		(fp_line
			(start 0.87503 1.525016)
			(end -0.87503 1.525016)
			(stroke
				(width 0.1)
				(type default)
			)
			(layer "F.Fab")
		)
		(fp_line
			(start -0.87503 1.525016)
			(end -0.87503 -1.525016)
			(stroke
				(width 0.1)
				(type default)
			)
			(layer "F.Fab")
		)
		(fp_poly
			(pts
				(xy -2.9718 -1.33096) (xy -2.9718 -0.56896) (xy -2.2098 -0.94996)
			)
			(stroke
				(width 0)
				(type default)
			)
			(fill yes)
			(layer "F.Fab")
		)
		(pad "1" smd rect
			(at -1.35001 -0.94996)
			(size 0.6096 1.0668)
			(layers "F.Cu" "F.Mask" "F.Paste")
			(net "PWRGD_P1V0_AUX_DELAY_R1")
		)
		(pad "2" smd rect
			(at -1.35001 0)
			(size 0.6096 1.0668)
			(layers "F.Cu" "F.Mask" "F.Paste")
			(net "GND")
		)
		(pad "3" smd rect
			(at -1.35001 0.94996)
			(size 0.6096 1.0668)
			(layers "F.Cu" "F.Mask" "F.Paste")
			(net "PWRGD_P1V0_AUX_R2")
		)
		(pad "4" smd rect
			(at 1.35001 0.94996)
			(size 0.6096 1.0668)
			(layers "F.Cu" "F.Mask" "F.Paste")
			(net "U43_CT")
		)
		(pad "5" smd rect
			(at 1.35001 0)
			(size 0.6096 1.0668)
			(layers "F.Cu" "F.Mask" "F.Paste")
			(net "P1V0_AUX")
		)
		(pad "6" smd rect
			(at 1.35001 -0.94996)
			(size 0.6096 1.0668)
			(layers "F.Cu" "F.Mask" "F.Paste")
			(net "P3V3_AUX")
		)
	)
)
